# T6G (Grand Teton) — schematic netlist excerpt (pin names and nets, part order shuffled) for the footprints in the layout excerpt that follows; sources: Cadence DE-HDL packaged netlist, KiCad conversion of 04192023_DAF0TMB3IC0_F0TG_MB_C_brd_V02_OCP.brd

PR2528  Q_RES  10 1% CHIP  pkg 0402LF  page 266 : A = P12V_HSC_GATE_G1 ; B = P12V_HSC_GATE2
PC219_1  Q_CAP  22UF 16V 20% X6S  pkg C0805  page 208 : A = SW_P12V_AUX_PVDD11_S3_P0_FLT ; B = GND
R1743  Q_RES  22 1% CHIP  pkg 0402LF  page 171 : A = JTAG_SCM_PLD_R_TDO ; B = JTAG_SCM_PLD_TDO

(kicad_pcb
	(version 20260206)
	(generator "pcbnew")
	(generator_version "10.0")
	(general
		(thickness 1.6)
		(legacy_teardrops no)
	)
	(paper "A4")
	(title_block
		(title "04192023_DAF0TMB3IC0_F0TG_MB_C_brd_V02_OCP.brd")
		(comment 1 "Grand Teton / footprints 4032-4034 of 8354")
	)
	(layers
		(0 "F.Cu" signal "TOP")
		(4 "In1.Cu" signal "GND")
		(6 "In2.Cu" signal "IN1")
		(8 "In3.Cu" signal "GND1")
		(10 "In4.Cu" signal "IN2")
		(12 "In5.Cu" signal "GND2")
		(14 "In6.Cu" signal "IN3")
		(16 "In7.Cu" signal "GND3")
		(18 "In8.Cu" signal "VCC")
		(20 "In9.Cu" signal "VCC1")
		(22 "In10.Cu" signal "GND4")
		(24 "In11.Cu" signal "IN4")
		(26 "In12.Cu" signal "GND5")
		(28 "In13.Cu" signal "IN5")
		(30 "In14.Cu" signal "GND6")
		(32 "In15.Cu" signal "IN6")
		(34 "In16.Cu" signal "GND7")
		(2 "B.Cu" signal "BOTTOM")
		(9 "F.Adhes" user "F.Adhesive")
		(11 "B.Adhes" user "B.Adhesive")
		(13 "F.Paste" user "Package Geometry/Pastemask Top")
		(15 "B.Paste" user "Package Geometry/Pastemask Bottom")
		(5 "F.SilkS" user "Ref Des/Silkscreen Top")
		(7 "B.SilkS" user "Ref Des/Silkscreen Bottom")
		(1 "F.Mask" user "Board Geometry/Soldermask Top")
		(3 "B.Mask" user "Board Geometry/Soldermask Bottom")
		(17 "Dwgs.User" user "User.Drawings")
		(19 "Cmts.User" user "User.Comments")
		(21 "Eco1.User" user "User.Eco1")
		(23 "Eco2.User" user "User.Eco2")
		(25 "Edge.Cuts" user "Board Geometry/Outline")
		(27 "Margin" user)
		(31 "F.CrtYd" user "Package Geometry/Place Bound Top")
		(29 "B.CrtYd" user "Package Geometry/Place Bound Bottom")
		(35 "F.Fab" user "Ref Des/Assembly Top")
		(33 "B.Fab" user "Ref Des/Assembly Bottom")
	)
	(footprint ""
		(layer "F.Cu")
		(at 255.831086 -380.66853)
		(property "Reference" "PR2528"
			(at 0 0 0)
			(layer "F.SilkS")
			(hide yes)
			(effects
				(font
					(size 1.27 1.27)
				)
			)
		)
		(property "Value" ""
			(at 0 0 0)
			(layer "F.Fab")
			(effects
				(font
					(size 1.27 1.27)
				)
			)
		)
		(duplicate_pad_numbers_are_jumpers no)
		(fp_line
			(start -0.7874 -0.4064)
			(end 0.7874 -0.4064)
			(stroke
				(width 0.1524)
				(type default)
			)
			(layer "F.SilkS")
		)
		(fp_line
			(start -0.7874 0.4064)
			(end -0.7874 -0.4064)
			(stroke
				(width 0.1524)
				(type default)
			)
			(layer "F.SilkS")
		)
		(fp_line
			(start 0.7874 -0.4064)
			(end 0.7874 0.4064)
			(stroke
				(width 0.1524)
				(type default)
			)
			(layer "F.SilkS")
		)
		(fp_line
			(start 0.7874 0.4064)
			(end -0.7874 0.4064)
			(stroke
				(width 0.1524)
				(type default)
			)
			(layer "F.SilkS")
		)
		(fp_line
			(start -0.67945 -0.305054)
			(end -0.12065 -0.305054)
			(stroke
				(width 0.1)
				(type default)
			)
			(layer "F.Fab")
		)
		(fp_line
			(start -0.67945 0.3048)
			(end -0.67945 -0.305054)
			(stroke
				(width 0.1)
				(type default)
			)
			(layer "F.Fab")
		)
		(fp_line
			(start -0.12065 -0.305054)
			(end -0.12065 -0.2794)
			(stroke
				(width 0.1)
				(type default)
			)
			(layer "F.Fab")
		)
		(fp_line
			(start -0.12065 -0.2794)
			(end 0.12065 -0.2794)
			(stroke
				(width 0.1)
				(type default)
			)
			(layer "F.Fab")
		)
		(fp_line
			(start -0.12065 0.2794)
			(end -0.12065 0.3048)
			(stroke
				(width 0.1)
				(type default)
			)
			(layer "F.Fab")
		)
		(fp_line
			(start -0.12065 0.3048)
			(end -0.67945 0.3048)
			(stroke
				(width 0.1)
				(type default)
			)
			(layer "F.Fab")
		)
		(fp_line
			(start 0.120396 0.2794)
			(end -0.12065 0.2794)
			(stroke
				(width 0.1)
				(type default)
			)
			(layer "F.Fab")
		)
		(fp_line
			(start 0.120396 0.3048)
			(end 0.120396 0.2794)
			(stroke
				(width 0.1)
				(type default)
			)
			(layer "F.Fab")
		)
		(fp_line
			(start 0.12065 -0.3048)
			(end 0.67945 -0.3048)
			(stroke
				(width 0.1)
				(type default)
			)
			(layer "F.Fab")
		)
		(fp_line
			(start 0.12065 -0.2794)
			(end 0.12065 -0.3048)
			(stroke
				(width 0.1)
				(type default)
			)
			(layer "F.Fab")
		)
		(fp_line
			(start 0.67945 -0.3048)
			(end 0.67945 0.3048)
			(stroke
				(width 0.1)
				(type default)
			)
			(layer "F.Fab")
		)
		(fp_line
			(start 0.67945 0.3048)
			(end 0.120396 0.3048)
			(stroke
				(width 0.1)
				(type default)
			)
			(layer "F.Fab")
		)
		(pad "1" smd circle
			(at -0.40005 0)
			(size 0 0)
			(layers "F.Cu" "F.Mask" "F.Paste")
			(net "P12V_HSC_GATE_G1")
		)
		(pad "2" smd circle
			(at 0.40005 0)
			(size 0 0)
			(layers "F.Cu" "F.Mask" "F.Paste")
			(net "P12V_HSC_GATE2")
		)
	)
	(footprint ""
		(layer "F.Cu")
		(at 425.896532 -358.570276 180)
		(property "Reference" "PC219_1"
			(at 0 0 180)
			(layer "F.SilkS")
			(hide yes)
			(effects
				(font
					(size 1.27 1.27)
				)
			)
		)
		(property "Value" ""
			(at 0 0 180)
			(layer "F.Fab")
			(effects
				(font
					(size 1.27 1.27)
				)
			)
		)
		(duplicate_pad_numbers_are_jumpers no)
		(fp_line
			(start 1.524 0.762)
			(end -1.524 0.762)
			(stroke
				(width 0.1524)
				(type default)
			)
			(layer "F.SilkS")
		)
		(fp_line
			(start 1.524 -0.762)
			(end 1.524 0.762)
			(stroke
				(width 0.1524)
				(type default)
			)
			(layer "F.SilkS")
		)
		(fp_line
			(start -1.524 0.762)
			(end -1.524 -0.762)
			(stroke
				(width 0.1524)
				(type default)
			)
			(layer "F.SilkS")
		)
		(fp_line
			(start -1.524 -0.762)
			(end 1.524 -0.762)
			(stroke
				(width 0.1524)
				(type default)
			)
			(layer "F.SilkS")
		)
		(fp_line
			(start 1.1049 0.724916)
			(end 1.1049 -0.724916)
			(stroke
				(width 0.1)
				(type default)
			)
			(layer "F.Fab")
		)
		(fp_line
			(start 1.1049 -0.724916)
			(end -1.1049 -0.724916)
			(stroke
				(width 0.1)
				(type default)
			)
			(layer "F.Fab")
		)
		(fp_line
			(start -1.1049 0.724916)
			(end 1.1049 0.724916)
			(stroke
				(width 0.1)
				(type default)
			)
			(layer "F.Fab")
		)
		(fp_line
			(start -1.1049 -0.724916)
			(end -1.1049 0.724916)
			(stroke
				(width 0.1)
				(type default)
			)
			(layer "F.Fab")
		)
		(pad "1" smd rect
			(at -0.889 0)
			(size 1.016 1.27)
			(layers "F.Cu" "F.Mask" "F.Paste")
			(net "SW_P12V_AUX_PVDD11_S3_P0_FLT")
		)
		(pad "2" smd rect
			(at 0.889 0)
			(size 1.016 1.27)
			(layers "F.Cu" "F.Mask" "F.Paste")
			(net "GND")
		)
	)
	(footprint ""
		(layer "F.Cu")
		(at 125.992636 -61.767212 180)
		(property "Reference" "R1743"
			(at 0 0 180)
			(layer "F.SilkS")
			(hide yes)
			(effects
				(font
					(size 1.27 1.27)
				)
			)
		)
		(property "Value" ""
			(at 0 0 180)
			(layer "F.Fab")
			(effects
				(font
					(size 1.27 1.27)
				)
			)
		)
		(duplicate_pad_numbers_are_jumpers no)
		(fp_line
			(start 0.7874 0.4064)
			(end -0.7874 0.4064)
			(stroke
				(width 0.1524)
				(type default)
			)
			(layer "F.SilkS")
		)
		(fp_line
			(start 0.7874 -0.4064)
			(end 0.7874 0.4064)
			(stroke
				(width 0.1524)
				(type default)
			)
			(layer "F.SilkS")
		)
		(fp_line
			(start -0.7874 0.4064)
			(end -0.7874 -0.4064)
			(stroke
				(width 0.1524)
				(type default)
			)
			(layer "F.SilkS")
		)
		(fp_line
			(start -0.7874 -0.4064)
			(end 0.7874 -0.4064)
			(stroke
				(width 0.1524)
				(type default)
			)
			(layer "F.SilkS")
		)
		(fp_line
			(start 0.67945 0.3048)
			(end 0.120396 0.3048)
			(stroke
				(width 0.1)
				(type default)
			)
			(layer "F.Fab")
		)
		(fp_line
			(start 0.67945 -0.3048)
			(end 0.67945 0.3048)
			(stroke
				(width 0.1)
				(type default)
			)
			(layer "F.Fab")
		)
		(fp_line
			(start 0.12065 -0.2794)
			(end 0.12065 -0.3048)
			(stroke
				(width 0.1)
				(type default)
			)
			(layer "F.Fab")
		)
		(fp_line
			(start 0.12065 -0.3048)
			(end 0.67945 -0.3048)
			(stroke
				(width 0.1)
				(type default)
			)
			(layer "F.Fab")
		)
		(fp_line
			(start 0.120396 0.3048)
			(end 0.120396 0.2794)
			(stroke
				(width 0.1)
				(type default)
			)
			(layer "F.Fab")
		)
		(fp_line
			(start 0.120396 0.2794)
			(end -0.12065 0.2794)
			(stroke
				(width 0.1)
				(type default)
			)
			(layer "F.Fab")
		)
		(fp_line
			(start -0.12065 0.3048)
			(end -0.67945 0.3048)
			(stroke
				(width 0.1)
				(type default)
			)
			(layer "F.Fab")
		)
		(fp_line
			(start -0.12065 0.2794)
			(end -0.12065 0.3048)
			(stroke
				(width 0.1)
				(type default)
			)
			(layer "F.Fab")
		)
		(fp_line
			(start -0.12065 -0.2794)
			(end 0.12065 -0.2794)
			(stroke
				(width 0.1)
				(type default)
			)
			(layer "F.Fab")
		)
		(fp_line
			(start -0.12065 -0.305054)
			(end -0.12065 -0.2794)
			(stroke
				(width 0.1)
				(type default)
			)
			(layer "F.Fab")
		)
		(fp_line
			(start -0.67945 0.3048)
			(end -0.67945 -0.305054)
			(stroke
				(width 0.1)
				(type default)
			)
			(layer "F.Fab")
		)
		(fp_line
			(start -0.67945 -0.305054)
			(end -0.12065 -0.305054)
			(stroke
				(width 0.1)
				(type default)
			)
			(layer "F.Fab")
		)
		(pad "1" smd circle
			(at -0.40005 0 180)
			(size 0 0)
			(layers "F.Cu" "F.Mask" "F.Paste")
			(net "JTAG_SCM_PLD_R_TDO")
		)
		(pad "2" smd circle
			(at 0.40005 0 180)
			(size 0 0)
			(layers "F.Cu" "F.Mask" "F.Paste")
			(net "JTAG_SCM_PLD_TDO")
		)
	)
)
